FILE_TYPE=LIBRARY_PARTS;
primitive 'MPQ8633AGLEC807Z';
  pin
    'VIN1':
      PIN_NUMBER='(10)';
      INPUT_LOAD='(-0.01,0.01)';
    'PGOOD':
      PIN_NUMBER='(9)';
      OUTPUT_LOAD='(1.0,-1.0)';
    'PGND':
      PIN_NUMBER='(11_18)';
      PINUSE='POWER';
      NO_LOAD_CHECK='Both';
      NO_IO_CHECK='Both';
      NO_ASSERT_CHECK='TRUE';
      NO_DIR_CHECK='TRUE';
      ALLOW_CONNECT='TRUE';
    'EN':
      PIN_NUMBER='(8)';
      INPUT_LOAD='(-0.01,0.01)';
    'BST':
      PIN_NUMBER='(1)';
      INPUT_LOAD='(-0.01,0.01)';
    'FB':
      PIN_NUMBER='(7)';
      INPUT_LOAD='(-0.01,0.01)';
    'AGND':
      PIN_NUMBER='(2)';
      PINUSE='POWER';
      NO_LOAD_CHECK='Both';
      NO_IO_CHECK='Both';
      NO_ASSERT_CHECK='TRUE';
      NO_DIR_CHECK='TRUE';
      ALLOW_CONNECT='TRUE';
    'VCC':
      PIN_NUMBER='(19)';
      PINUSE='POWER';
      NO_LOAD_CHECK='Both';
      NO_IO_CHECK='Both';
      NO_ASSERT_CHECK='TRUE';
      NO_DIR_CHECK='TRUE';
      ALLOW_CONNECT='TRUE';
    'RGND':
      PIN_NUMBER='(6)';
      PINUSE='POWER';
      NO_LOAD_CHECK='Both';
      NO_IO_CHECK='Both';
      NO_ASSERT_CHECK='TRUE';
      NO_DIR_CHECK='TRUE';
      ALLOW_CONNECT='TRUE';
    'SW':
      PIN_NUMBER='(20)';
      OUTPUT_LOAD='(1.0,-1.0)';
    'TRK_REF':
      PIN_NUMBER='(5)';
      INPUT_LOAD='(-0.01,0.01)';
    'MODE':
      PIN_NUMBER='(4)';
      INPUT_LOAD='(-0.01,0.01)';
    'CS':
      PIN_NUMBER='(3)';
      INPUT_LOAD='(-0.01,0.01)';
    'VIN2':
      PIN_NUMBER='(21)';
      INPUT_LOAD='(-0.01,0.01)';
  end_pin;
  body
    PART_NAME='MPQ8633AGLEC807Z';
    BODY_NAME='MPQ8633AGLEC807Z';
    PHYS_DES_PREFIX='U';
    CLASS='IC';
  end_body;
end_primitive;

END.
